(kicad_pcb
	(version 20260206)
	(generator "pcbnew")
	(generator_version "10.0")
	(general
		(thickness 1.6)
		(legacy_teardrops no)
	)
	(paper "A4")
	(title_block
		(title "9054_F0T_PDB_BD_GPU_F_V04_1213_1550_OCP.brd")
		(comment 1 "Grand Teton / footprints 458-462 of 608")
	)
	(layers
		(0 "F.Cu" signal "TOP")
		(4 "In1.Cu" signal "GND")
		(6 "In2.Cu" signal "IN1")
		(8 "In3.Cu" signal "GND1")
		(10 "In4.Cu" signal "VCC")
		(12 "In5.Cu" signal "VCC1")
		(14 "In6.Cu" signal "GND2")
		(16 "In7.Cu" signal "IN2")
		(18 "In8.Cu" signal "GND3")
		(2 "B.Cu" signal "BOTTOM")
		(9 "F.Adhes" user "F.Adhesive")
		(11 "B.Adhes" user "B.Adhesive")
		(13 "F.Paste" user "Package Geometry/Pastemask Top")
		(15 "B.Paste" user "Package Geometry/Pastemask Bottom")
		(5 "F.SilkS" user "Ref Des/Silkscreen Top")
		(7 "B.SilkS" user "Ref Des/Silkscreen Bottom")
		(1 "F.Mask" user "Board Geometry/Soldermask Top")
		(3 "B.Mask" user "Board Geometry/Soldermask Bottom")
		(17 "Dwgs.User" user "User.Drawings")
		(19 "Cmts.User" user "User.Comments")
		(21 "Eco1.User" user "User.Eco1")
		(23 "Eco2.User" user "User.Eco2")
		(25 "Edge.Cuts" user "Board Geometry/Outline")
		(27 "Margin" user)
		(31 "F.CrtYd" user "Package Geometry/Place Bound Top")
		(29 "B.CrtYd" user "Package Geometry/Place Bound Bottom")
		(35 "F.Fab" user "Ref Des/Assembly Top")
		(33 "B.Fab" user "Ref Des/Assembly Bottom")
	)
	(footprint ""
		(layer "B.Cu")
		(at 338.8614 -50.5206 -90)
		(property "Reference" "PD15"
			(at 4.0386 1.57607 270)
			(unlocked yes)
			(layer "B.SilkS")
			(effects
				(font
					(size 0.7874 0.5842)
					(thickness 0.1524)
				)
				(justify left mirror)
			)
		)
		(property "Value" ""
			(at 0 0 90)
			(layer "B.Fab")
			(effects
				(font
					(size 1.27 1.27)
				)
				(justify mirror)
			)
		)
		(duplicate_pad_numbers_are_jumpers no)
		(fp_line
			(start -2.032 0.7112)
			(end 1.651 0.7112)
			(stroke
				(width 0.1524)
				(type default)
			)
			(layer "B.SilkS")
		)
		(fp_line
			(start 1.651 0.7112)
			(end 1.651 -0.7112)
			(stroke
				(width 0.1524)
				(type default)
			)
			(layer "B.SilkS")
		)
		(fp_line
			(start -1.778 0.6858)
			(end -1.778 -0.6858)
			(stroke
				(width 0.1524)
				(type default)
			)
			(layer "B.SilkS")
		)
		(fp_line
			(start 0.299974 0.500126)
			(end -0.199898 0)
			(stroke
				(width 0.1524)
				(type default)
			)
			(layer "B.SilkS")
		)
		(fp_line
			(start -0.199898 0)
			(end 0.299974 -0.500126)
			(stroke
				(width 0.1524)
				(type default)
			)
			(layer "B.SilkS")
		)
		(fp_line
			(start -0.299974 -0.500126)
			(end -0.299974 0.500126)
			(stroke
				(width 0.1524)
				(type default)
			)
			(layer "B.SilkS")
		)
		(fp_line
			(start 0.299974 -0.500126)
			(end 0.299974 0.500126)
			(stroke
				(width 0.1524)
				(type default)
			)
			(layer "B.SilkS")
		)
		(fp_line
			(start -1.905 -0.6858)
			(end -1.905 0.6858)
			(stroke
				(width 0.1524)
				(type default)
			)
			(layer "B.SilkS")
		)
		(fp_line
			(start -1.651 -0.6858)
			(end -1.651 0.6858)
			(stroke
				(width 0.1524)
				(type default)
			)
			(layer "B.SilkS")
		)
		(fp_line
			(start -2.032 -0.7112)
			(end -2.032 0.7112)
			(stroke
				(width 0.1524)
				(type default)
			)
			(layer "B.SilkS")
		)
		(fp_line
			(start 1.651 -0.7112)
			(end -2.032 -0.7112)
			(stroke
				(width 0.1524)
				(type default)
			)
			(layer "B.SilkS")
		)
		(fp_line
			(start -0.899922 0.700024)
			(end 0.899922 0.700024)
			(stroke
				(width 0.1)
				(type default)
			)
			(layer "B.Fab")
		)
		(fp_line
			(start 0.899922 0.700024)
			(end 0.899922 0.175006)
			(stroke
				(width 0.1)
				(type default)
			)
			(layer "B.Fab")
		)
		(fp_line
			(start 0.299974 0.500126)
			(end -0.199898 0)
			(stroke
				(width 0.1)
				(type default)
			)
			(layer "B.Fab")
		)
		(fp_line
			(start -1.35001 0.175006)
			(end -0.899922 0.175006)
			(stroke
				(width 0.1)
				(type default)
			)
			(layer "B.Fab")
		)
		(fp_line
			(start -0.899922 0.175006)
			(end -0.899922 0.700024)
			(stroke
				(width 0.1)
				(type default)
			)
			(layer "B.Fab")
		)
		(fp_line
			(start 0.899922 0.175006)
			(end 1.35001 0.175006)
			(stroke
				(width 0.1)
				(type default)
			)
			(layer "B.Fab")
		)
		(fp_line
			(start 1.35001 0.175006)
			(end 1.35001 -0.225044)
			(stroke
				(width 0.1)
				(type default)
			)
			(layer "B.Fab")
		)
		(fp_line
			(start -0.199898 0)
			(end 0.299974 -0.500126)
			(stroke
				(width 0.1)
				(type default)
			)
			(layer "B.Fab")
		)
		(fp_line
			(start -1.35001 -0.225044)
			(end -1.35001 0.175006)
			(stroke
				(width 0.1)
				(type default)
			)
			(layer "B.Fab")
		)
		(fp_line
			(start -0.899922 -0.225044)
			(end -1.35001 -0.225044)
			(stroke
				(width 0.1)
				(type default)
			)
			(layer "B.Fab")
		)
		(fp_line
			(start 0.899922 -0.225044)
			(end 0.899922 -0.700024)
			(stroke
				(width 0.1)
				(type default)
			)
			(layer "B.Fab")
		)
		(fp_line
			(start 1.35001 -0.225044)
			(end 0.899922 -0.225044)
			(stroke
				(width 0.1)
				(type default)
			)
			(layer "B.Fab")
		)
		(fp_line
			(start -0.299974 -0.500126)
			(end -0.299974 0.500126)
			(stroke
				(width 0.1)
				(type default)
			)
			(layer "B.Fab")
		)
		(fp_line
			(start 0.299974 -0.500126)
			(end 0.299974 0.500126)
			(stroke
				(width 0.1)
				(type default)
			)
			(layer "B.Fab")
		)
		(fp_line
			(start -0.899922 -0.700024)
			(end -0.899922 -0.225044)
			(stroke
				(width 0.1)
				(type default)
			)
			(layer "B.Fab")
		)
		(fp_line
			(start 0.899922 -0.700024)
			(end -0.899922 -0.700024)
			(stroke
				(width 0.1)
				(type default)
			)
			(layer "B.Fab")
		)
		(fp_text user "-"
			(at -1.8288 -0.24765 270)
			(unlocked yes)
			(layer "B.SilkS")
			(effects
				(font
					(size 1.905 1.4224)
					(thickness 0.1524)
				)
				(justify left mirror)
			)
		)
		(fp_text user "+"
			(at 2.8956 -0.70485 270)
			(unlocked yes)
			(layer "B.SilkS")
			(effects
				(font
					(size 1.905 1.4224)
					(thickness 0.1524)
				)
				(justify left mirror)
			)
		)
		(fp_text user "+"
			(at 2.794 -0.19685 270)
			(unlocked yes)
			(layer "B.Fab")
			(effects
				(font
					(size 1.905 1.4224)
					(thickness 0.1524)
				)
				(justify left mirror)
			)
		)
		(fp_text user "-"
			(at -1.8288 -0.24765 270)
			(unlocked yes)
			(layer "B.Fab")
			(effects
				(font
					(size 1.905 1.4224)
					(thickness 0.1524)
				)
				(justify left mirror)
			)
		)
		(pad "1" smd rect
			(at 1.0922 0 270)
			(size 0.8128 0.8636)
			(layers "B.Cu" "B.Mask" "B.Paste")
			(net "P52V_HS1_4287_GATE_R")
		)
		(pad "2" smd rect
			(at -1.0922 0 90)
			(size 0.8128 0.8636)
			(layers "B.Cu" "B.Mask" "B.Paste")
			(net "P52V_HS1_GATE_R1")
		)
	)
	(footprint ""
		(layer "B.Cu")
		(at 413.639 -36.195 180)
		(property "Reference" "R5935"
			(at 0 0 0)
			(layer "B.SilkS")
			(hide yes)
			(effects
				(font
					(size 1.27 1.27)
				)
				(justify mirror)
			)
		)
		(property "Value" ""
			(at 0 0 0)
			(layer "B.Fab")
			(effects
				(font
					(size 1.27 1.27)
				)
				(justify mirror)
			)
		)
		(duplicate_pad_numbers_are_jumpers no)
		(fp_line
			(start 0.7874 0.4064)
			(end 0.7874 -0.4064)
			(stroke
				(width 0.1524)
				(type default)
			)
			(layer "B.SilkS")
		)
		(fp_line
			(start 0.7874 -0.4064)
			(end -0.7874 -0.4064)
			(stroke
				(width 0.1524)
				(type default)
			)
			(layer "B.SilkS")
		)
		(fp_line
			(start -0.7874 0.4064)
			(end 0.7874 0.4064)
			(stroke
				(width 0.1524)
				(type default)
			)
			(layer "B.SilkS")
		)
		(fp_line
			(start -0.7874 -0.4064)
			(end -0.7874 0.4064)
			(stroke
				(width 0.1524)
				(type default)
			)
			(layer "B.SilkS")
		)
		(fp_line
			(start 0.67945 0.3048)
			(end 0.67945 -0.305054)
			(stroke
				(width 0.1)
				(type default)
			)
			(layer "B.Fab")
		)
		(fp_line
			(start 0.67945 -0.305054)
			(end 0.12065 -0.305054)
			(stroke
				(width 0.1)
				(type default)
			)
			(layer "B.Fab")
		)
		(fp_line
			(start 0.12065 0.3048)
			(end 0.67945 0.3048)
			(stroke
				(width 0.1)
				(type default)
			)
			(layer "B.Fab")
		)
		(fp_line
			(start 0.12065 0.2794)
			(end 0.12065 0.3048)
			(stroke
				(width 0.1)
				(type default)
			)
			(layer "B.Fab")
		)
		(fp_line
			(start 0.12065 -0.2794)
			(end -0.12065 -0.2794)
			(stroke
				(width 0.1)
				(type default)
			)
			(layer "B.Fab")
		)
		(fp_line
			(start 0.12065 -0.305054)
			(end 0.12065 -0.2794)
			(stroke
				(width 0.1)
				(type default)
			)
			(layer "B.Fab")
		)
		(fp_line
			(start -0.120396 0.3048)
			(end -0.120396 0.2794)
			(stroke
				(width 0.1)
				(type default)
			)
			(layer "B.Fab")
		)
		(fp_line
			(start -0.120396 0.2794)
			(end 0.12065 0.2794)
			(stroke
				(width 0.1)
				(type default)
			)
			(layer "B.Fab")
		)
		(fp_line
			(start -0.12065 -0.2794)
			(end -0.12065 -0.3048)
			(stroke
				(width 0.1)
				(type default)
			)
			(layer "B.Fab")
		)
		(fp_line
			(start -0.12065 -0.3048)
			(end -0.67945 -0.3048)
			(stroke
				(width 0.1)
				(type default)
			)
			(layer "B.Fab")
		)
		(fp_line
			(start -0.67945 0.3048)
			(end -0.120396 0.3048)
			(stroke
				(width 0.1)
				(type default)
			)
			(layer "B.Fab")
		)
		(fp_line
			(start -0.67945 -0.3048)
			(end -0.67945 0.3048)
			(stroke
				(width 0.1)
				(type default)
			)
			(layer "B.Fab")
		)
		(pad "1" smd circle
			(at 0.40005 0)
			(size 0 0)
			(layers "B.Cu" "B.Mask" "B.Paste")
			(net "P3V3_AUX")
		)
		(pad "2" smd circle
			(at -0.40005 0)
			(size 0 0)
			(layers "B.Cu" "B.Mask" "B.Paste")
			(net "PCA9555_2_A1")
		)
	)
	(footprint ""
		(layer "B.Cu")
		(at 175.306736 -77.851)
		(property "Reference" "R5881"
			(at 0 0 0)
			(layer "B.SilkS")
			(hide yes)
			(effects
				(font
					(size 1.27 1.27)
				)
				(justify mirror)
			)
		)
		(property "Value" ""
			(at 0 0 0)
			(layer "B.Fab")
			(effects
				(font
					(size 1.27 1.27)
				)
				(justify mirror)
			)
		)
		(duplicate_pad_numbers_are_jumpers no)
		(fp_line
			(start -0.7874 -0.4064)
			(end -0.7874 0.4064)
			(stroke
				(width 0.1524)
				(type default)
			)
			(layer "B.SilkS")
		)
		(fp_line
			(start -0.7874 0.4064)
			(end 0.7874 0.4064)
			(stroke
				(width 0.1524)
				(type default)
			)
			(layer "B.SilkS")
		)
		(fp_line
			(start 0.7874 -0.4064)
			(end -0.7874 -0.4064)
			(stroke
				(width 0.1524)
				(type default)
			)
			(layer "B.SilkS")
		)
		(fp_line
			(start 0.7874 0.4064)
			(end 0.7874 -0.4064)
			(stroke
				(width 0.1524)
				(type default)
			)
			(layer "B.SilkS")
		)
		(fp_line
			(start -0.67945 -0.3048)
			(end -0.67945 0.3048)
			(stroke
				(width 0.1)
				(type default)
			)
			(layer "B.Fab")
		)
		(fp_line
			(start -0.67945 0.3048)
			(end -0.120396 0.3048)
			(stroke
				(width 0.1)
				(type default)
			)
			(layer "B.Fab")
		)
		(fp_line
			(start -0.12065 -0.3048)
			(end -0.67945 -0.3048)
			(stroke
				(width 0.1)
				(type default)
			)
			(layer "B.Fab")
		)
		(fp_line
			(start -0.12065 -0.2794)
			(end -0.12065 -0.3048)
			(stroke
				(width 0.1)
				(type default)
			)
			(layer "B.Fab")
		)
		(fp_line
			(start -0.120396 0.2794)
			(end 0.12065 0.2794)
			(stroke
				(width 0.1)
				(type default)
			)
			(layer "B.Fab")
		)
		(fp_line
			(start -0.120396 0.3048)
			(end -0.120396 0.2794)
			(stroke
				(width 0.1)
				(type default)
			)
			(layer "B.Fab")
		)
		(fp_line
			(start 0.12065 -0.305054)
			(end 0.12065 -0.2794)
			(stroke
				(width 0.1)
				(type default)
			)
			(layer "B.Fab")
		)
		(fp_line
			(start 0.12065 -0.2794)
			(end -0.12065 -0.2794)
			(stroke
				(width 0.1)
				(type default)
			)
			(layer "B.Fab")
		)
		(fp_line
			(start 0.12065 0.2794)
			(end 0.12065 0.3048)
			(stroke
				(width 0.1)
				(type default)
			)
			(layer "B.Fab")
		)
		(fp_line
			(start 0.12065 0.3048)
			(end 0.67945 0.3048)
			(stroke
				(width 0.1)
				(type default)
			)
			(layer "B.Fab")
		)
		(fp_line
			(start 0.67945 -0.305054)
			(end 0.12065 -0.305054)
			(stroke
				(width 0.1)
				(type default)
			)
			(layer "B.Fab")
		)
		(fp_line
			(start 0.67945 0.3048)
			(end 0.67945 -0.305054)
			(stroke
				(width 0.1)
				(type default)
			)
			(layer "B.Fab")
		)
		(pad "1" smd circle
			(at 0.40005 0 180)
			(size 0 0)
			(layers "B.Cu" "B.Mask" "B.Paste")
			(net "PWRGD_P52V_HS2_PG")
		)
		(pad "2" smd circle
			(at -0.40005 0 180)
			(size 0 0)
			(layers "B.Cu" "B.Mask" "B.Paste")
			(net "GND1_FIELD_SIGNAL")
		)
	)
	(footprint ""
		(layer "B.Cu")
		(at 278.4094 -67.945)
		(property "Reference" "R146"
			(at 0 0 0)
			(layer "B.SilkS")
			(hide yes)
			(effects
				(font
					(size 1.27 1.27)
				)
				(justify mirror)
			)
		)
		(property "Value" ""
			(at 0 0 0)
			(layer "B.Fab")
			(effects
				(font
					(size 1.27 1.27)
				)
				(justify mirror)
			)
		)
		(duplicate_pad_numbers_are_jumpers no)
		(fp_line
			(start -0.7874 -0.4064)
			(end -0.7874 0.4064)
			(stroke
				(width 0.1524)
				(type default)
			)
			(layer "B.SilkS")
		)
		(fp_line
			(start -0.7874 0.4064)
			(end 0.7874 0.4064)
			(stroke
				(width 0.1524)
				(type default)
			)
			(layer "B.SilkS")
		)
		(fp_line
			(start 0.7874 -0.4064)
			(end -0.7874 -0.4064)
			(stroke
				(width 0.1524)
				(type default)
			)
			(layer "B.SilkS")
		)
		(fp_line
			(start 0.7874 0.4064)
			(end 0.7874 -0.4064)
			(stroke
				(width 0.1524)
				(type default)
			)
			(layer "B.SilkS")
		)
		(fp_line
			(start -0.67945 -0.3048)
			(end -0.67945 0.3048)
			(stroke
				(width 0.1)
				(type default)
			)
			(layer "B.Fab")
		)
		(fp_line
			(start -0.67945 0.3048)
			(end -0.120396 0.3048)
			(stroke
				(width 0.1)
				(type default)
			)
			(layer "B.Fab")
		)
		(fp_line
			(start -0.12065 -0.3048)
			(end -0.67945 -0.3048)
			(stroke
				(width 0.1)
				(type default)
			)
			(layer "B.Fab")
		)
		(fp_line
			(start -0.12065 -0.2794)
			(end -0.12065 -0.3048)
			(stroke
				(width 0.1)
				(type default)
			)
			(layer "B.Fab")
		)
		(fp_line
			(start -0.120396 0.2794)
			(end 0.12065 0.2794)
			(stroke
				(width 0.1)
				(type default)
			)
			(layer "B.Fab")
		)
		(fp_line
			(start -0.120396 0.3048)
			(end -0.120396 0.2794)
			(stroke
				(width 0.1)
				(type default)
			)
			(layer "B.Fab")
		)
		(fp_line
			(start 0.12065 -0.305054)
			(end 0.12065 -0.2794)
			(stroke
				(width 0.1)
				(type default)
			)
			(layer "B.Fab")
		)
		(fp_line
			(start 0.12065 -0.2794)
			(end -0.12065 -0.2794)
			(stroke
				(width 0.1)
				(type default)
			)
			(layer "B.Fab")
		)
		(fp_line
			(start 0.12065 0.2794)
			(end 0.12065 0.3048)
			(stroke
				(width 0.1)
				(type default)
			)
			(layer "B.Fab")
		)
		(fp_line
			(start 0.12065 0.3048)
			(end 0.67945 0.3048)
			(stroke
				(width 0.1)
				(type default)
			)
			(layer "B.Fab")
		)
		(fp_line
			(start 0.67945 -0.305054)
			(end 0.12065 -0.305054)
			(stroke
				(width 0.1)
				(type default)
			)
			(layer "B.Fab")
		)
		(fp_line
			(start 0.67945 0.3048)
			(end 0.67945 -0.305054)
			(stroke
				(width 0.1)
				(type default)
			)
			(layer "B.Fab")
		)
		(pad "1" smd circle
			(at 0.40005 0 180)
			(size 0 0)
			(layers "B.Cu" "B.Mask" "B.Paste")
			(net "P3V3_AUX")
		)
		(pad "2" smd circle
			(at -0.40005 0 180)
			(size 0 0)
			(layers "B.Cu" "B.Mask" "B.Paste")
			(net "SMB_P52V_PDB_SCL_R1")
		)
	)
	(footprint ""
		(layer "B.Cu")
		(at 180.086 -53.848 180)
		(property "Reference" "R5896"
			(at 0 0 0)
			(layer "B.SilkS")
			(hide yes)
			(effects
				(font
					(size 1.27 1.27)
				)
				(justify mirror)
			)
		)
		(property "Value" ""
			(at 0 0 0)
			(layer "B.Fab")
			(effects
				(font
					(size 1.27 1.27)
				)
				(justify mirror)
			)
		)
		(duplicate_pad_numbers_are_jumpers no)
		(fp_line
			(start 0.7874 0.4064)
			(end 0.7874 -0.4064)
			(stroke
				(width 0.1524)
				(type default)
			)
			(layer "B.SilkS")
		)
		(fp_line
			(start 0.7874 -0.4064)
			(end -0.7874 -0.4064)
			(stroke
				(width 0.1524)
				(type default)
			)
			(layer "B.SilkS")
		)
		(fp_line
			(start -0.7874 0.4064)
			(end 0.7874 0.4064)
			(stroke
				(width 0.1524)
				(type default)
			)
			(layer "B.SilkS")
		)
		(fp_line
			(start -0.7874 -0.4064)
			(end -0.7874 0.4064)
			(stroke
				(width 0.1524)
				(type default)
			)
			(layer "B.SilkS")
		)
		(fp_line
			(start 0.67945 0.3048)
			(end 0.67945 -0.305054)
			(stroke
				(width 0.1)
				(type default)
			)
			(layer "B.Fab")
		)
		(fp_line
			(start 0.67945 -0.305054)
			(end 0.12065 -0.305054)
			(stroke
				(width 0.1)
				(type default)
			)
			(layer "B.Fab")
		)
		(fp_line
			(start 0.12065 0.3048)
			(end 0.67945 0.3048)
			(stroke
				(width 0.1)
				(type default)
			)
			(layer "B.Fab")
		)
		(fp_line
			(start 0.12065 0.2794)
			(end 0.12065 0.3048)
			(stroke
				(width 0.1)
				(type default)
			)
			(layer "B.Fab")
		)
		(fp_line
			(start 0.12065 -0.2794)
			(end -0.12065 -0.2794)
			(stroke
				(width 0.1)
				(type default)
			)
			(layer "B.Fab")
		)
		(fp_line
			(start 0.12065 -0.305054)
			(end 0.12065 -0.2794)
			(stroke
				(width 0.1)
				(type default)
			)
			(layer "B.Fab")
		)
		(fp_line
			(start -0.120396 0.3048)
			(end -0.120396 0.2794)
			(stroke
				(width 0.1)
				(type default)
			)
			(layer "B.Fab")
		)
		(fp_line
			(start -0.120396 0.2794)
			(end 0.12065 0.2794)
			(stroke
				(width 0.1)
				(type default)
			)
			(layer "B.Fab")
		)
		(fp_line
			(start -0.12065 -0.2794)
			(end -0.12065 -0.3048)
			(stroke
				(width 0.1)
				(type default)
			)
			(layer "B.Fab")
		)
		(fp_line
			(start -0.12065 -0.3048)
			(end -0.67945 -0.3048)
			(stroke
				(width 0.1)
				(type default)
			)
			(layer "B.Fab")
		)
		(fp_line
			(start -0.67945 0.3048)
			(end -0.120396 0.3048)
			(stroke
				(width 0.1)
				(type default)
			)
			(layer "B.Fab")
		)
		(fp_line
			(start -0.67945 -0.3048)
			(end -0.67945 0.3048)
			(stroke
				(width 0.1)
				(type default)
			)
			(layer "B.Fab")
		)
		(pad "1" smd circle
			(at 0.40005 0)
			(size 0 0)
			(layers "B.Cu" "B.Mask" "B.Paste")
			(net "GPU_HSC2_BUF_EN")
		)
		(pad "2" smd circle
			(at -0.40005 0)
			(size 0 0)
			(layers "B.Cu" "B.Mask" "B.Paste")
			(net "FM_HS2_EN_FUSE")
		)
	)
)
